(kicad_pcb
	(version 20241229)
	(generator "pcbnew")
	(generator_version "9.0")
	(general
		(thickness 1.599998)
		(legacy_teardrops no)
	)
	(paper "A4")
	(title_block
		(title "Artix - Datacenter Secure Control Module (DC-SCM)")
		(date "2024-11-06")
		(rev "1.1.3")
		(comment 9 "footprints 228-234 of 544")
	)
	(layers
		(0 "F.Cu" signal)
		(4 "In1.Cu" signal)
		(6 "In2.Cu" signal)
		(8 "In3.Cu" signal)
		(10 "In4.Cu" signal)
		(12 "In5.Cu" signal)
		(14 "In6.Cu" signal)
		(2 "B.Cu" signal)
		(9 "F.Adhes" user "F.Adhesive")
		(11 "B.Adhes" user "B.Adhesive")
		(13 "F.Paste" user)
		(15 "B.Paste" user)
		(5 "F.SilkS" user "F.Silkscreen")
		(7 "B.SilkS" user "B.Silkscreen")
		(1 "F.Mask" user)
		(3 "B.Mask" user)
		(17 "Dwgs.User" user "User.Drawings")
		(19 "Cmts.User" user "User.Comments")
		(21 "Eco1.User" user "User.Eco1")
		(23 "Eco2.User" user "User.Eco2")
		(25 "Edge.Cuts" user)
		(27 "Margin" user)
		(31 "F.CrtYd" user "F.Courtyard")
		(29 "B.CrtYd" user "B.Courtyard")
		(35 "F.Fab" user)
		(33 "B.Fab" user)
	)
	(footprint "antmicro-footprints:Oscillator_SMD_Abracon_ASEMB_3.2x2.5mm"
		(layer "F.Cu")
		(at 123.735 133.633 90)
		(property "Reference" "U23"
			(at -2.867 -0.985 180)
			(layer "F.SilkS")
			(effects
				(font
					(size 0.7 0.7)
					(thickness 0.15)
				)
				(justify left bottom)
			)
		)
		(property "Value" "Oscillator_24MHz_ASEMB"
			(at 20.284 4.161 90)
			(layer "F.Fab")
			(effects
				(font
					(size 0.7 0.7)
					(thickness 0.15)
				)
				(justify left bottom)
			)
		)
		(property "Datasheet" "https://abracon.com/Oscillators/ASEMB.pdf"
			(at 0 0 90)
			(layer "F.Fab")
			(hide yes)
			(effects
				(font
					(size 1.27 1.27)
					(thickness 0.15)
				)
			)
		)
		(property "Description" "MEMS Oscillator, Clock, Pure Silicon&trade;, 24 MHz, SMD, 3.2mm x 2.5mm, 50 ppm, 3.3 V, ASEMB, LVCMOS"
			(at 0 0 90)
			(layer "F.Fab")
			(hide yes)
			(effects
				(font
					(size 1.27 1.27)
					(thickness 0.15)
				)
			)
		)
		(property "Author" "Antmicro"
			(at 257.368 9.898 0)
			(layer "F.Fab")
			(hide yes)
			(effects
				(font
					(size 1 1)
					(thickness 0.15)
				)
			)
		)
		(property "License" "Apache-2.0"
			(at 257.368 9.898 0)
			(layer "F.Fab")
			(hide yes)
			(effects
				(font
					(size 1 1)
					(thickness 0.15)
				)
			)
		)
		(property "MPN" "ASEMB-24.000MHZ-LC-T"
			(at 257.368 9.898 0)
			(layer "F.Fab")
			(hide yes)
			(effects
				(font
					(size 1 1)
					(thickness 0.15)
				)
			)
		)
		(property "Manufacturer" "Abracon"
			(at 257.368 9.898 0)
			(layer "F.Fab")
			(hide yes)
			(effects
				(font
					(size 1 1)
					(thickness 0.15)
				)
			)
		)
		(property "Val" "24 MHz"
			(at 257.368 9.898 0)
			(layer "F.Fab")
			(hide yes)
			(effects
				(font
					(size 1 1)
					(thickness 0.15)
				)
			)
		)
		(sheetname "/Interfaces/")
		(sheetfile "interfaces.kicad_sch")
		(attr smd)
		(fp_circle
			(center -1.5748 -1.8034)
			(end -1.5248 -1.8034)
			(stroke
				(width 0.15)
				(type solid)
			)
			(fill yes)
			(layer "F.SilkS")
		)
		(fp_rect
			(start -1.752 -2.101)
			(end 1.749 2.1)
			(stroke
				(width 0.05)
				(type solid)
			)
			(fill no)
			(layer "F.CrtYd")
		)
		(fp_line
			(start -1.2192 -1.4224)
			(end -1.0668 -1.5748)
			(stroke
				(width 0.15)
				(type solid)
			)
			(layer "F.Fab")
		)
		(fp_rect
			(start -1.252 -1.601)
			(end 1.249 1.6)
			(stroke
				(width 0.15)
				(type solid)
			)
			(fill no)
			(layer "F.Fab")
		)
		(pad "1" smd rect
			(at -0.951 -1.049 90)
			(size 1 0.9)
			(layers "F.Cu" "F.Mask" "F.Paste")
			(net 2 "VCC3V3")
			(pinfunction "EN")
			(pintype "input")
		)
		(pad "2" smd rect
			(at -0.951 1.05 90)
			(size 1 0.9)
			(layers "F.Cu" "F.Mask" "F.Paste")
			(net 1 "GND")
			(pinfunction "GND")
			(pintype "power_in")
		)
		(pad "3" smd rect
			(at 0.948 1.05 90)
			(size 1 0.9)
			(layers "F.Cu" "F.Mask" "F.Paste")
			(net 656 "Net-(U18-XI)")
			(pinfunction "OUT")
			(pintype "output")
		)
		(pad "4" smd rect
			(at 0.948 -1.049 90)
			(size 1 0.9)
			(layers "F.Cu" "F.Mask" "F.Paste")
			(net 2 "VCC3V3")
			(pinfunction "VDD")
			(pintype "power_in")
		)
	)
	(footprint "antmicro-footprints:Oscillator_SMD_Abracon_ASEMB_3.2x2.5mm"
		(layer "F.Cu")
		(at 123.905 116.883 90)
		(property "Reference" "U24"
			(at -2.917 -0.905 180)
			(layer "F.SilkS")
			(effects
				(font
					(size 0.7 0.7)
					(thickness 0.15)
				)
				(justify left bottom)
			)
		)
		(property "Value" "Oscillator_24MHz_ASEMB"
			(at 20.284 4.161 90)
			(layer "F.Fab")
			(effects
				(font
					(size 0.7 0.7)
					(thickness 0.15)
				)
				(justify left bottom)
			)
		)
		(property "Datasheet" "https://abracon.com/Oscillators/ASEMB.pdf"
			(at 0 0 90)
			(layer "F.Fab")
			(hide yes)
			(effects
				(font
					(size 1.27 1.27)
					(thickness 0.15)
				)
			)
		)
		(property "Description" "MEMS Oscillator, Clock, Pure Silicon&trade;, 24 MHz, SMD, 3.2mm x 2.5mm, 50 ppm, 3.3 V, ASEMB, LVCMOS"
			(at 0 0 90)
			(layer "F.Fab")
			(hide yes)
			(effects
				(font
					(size 1.27 1.27)
					(thickness 0.15)
				)
			)
		)
		(property "Author" "Antmicro"
			(at 240.788 -7.022 0)
			(layer "F.Fab")
			(hide yes)
			(effects
				(font
					(size 1 1)
					(thickness 0.15)
				)
			)
		)
		(property "License" "Apache-2.0"
			(at 240.788 -7.022 0)
			(layer "F.Fab")
			(hide yes)
			(effects
				(font
					(size 1 1)
					(thickness 0.15)
				)
			)
		)
		(property "MPN" "ASEMB-24.000MHZ-LC-T"
			(at 240.788 -7.022 0)
			(layer "F.Fab")
			(hide yes)
			(effects
				(font
					(size 1 1)
					(thickness 0.15)
				)
			)
		)
		(property "Manufacturer" "Abracon"
			(at 240.788 -7.022 0)
			(layer "F.Fab")
			(hide yes)
			(effects
				(font
					(size 1 1)
					(thickness 0.15)
				)
			)
		)
		(property "Val" "24 MHz"
			(at 240.788 -7.022 0)
			(layer "F.Fab")
			(hide yes)
			(effects
				(font
					(size 1 1)
					(thickness 0.15)
				)
			)
		)
		(sheetname "/Interfaces/")
		(sheetfile "interfaces.kicad_sch")
		(attr smd)
		(fp_circle
			(center -1.5748 -1.8034)
			(end -1.5248 -1.8034)
			(stroke
				(width 0.15)
				(type solid)
			)
			(fill yes)
			(layer "F.SilkS")
		)
		(fp_rect
			(start -1.752 -2.101)
			(end 1.749 2.1)
			(stroke
				(width 0.05)
				(type solid)
			)
			(fill no)
			(layer "F.CrtYd")
		)
		(fp_line
			(start -1.2192 -1.4224)
			(end -1.0668 -1.5748)
			(stroke
				(width 0.15)
				(type solid)
			)
			(layer "F.Fab")
		)
		(fp_rect
			(start -1.252 -1.601)
			(end 1.249 1.6)
			(stroke
				(width 0.15)
				(type solid)
			)
			(fill no)
			(layer "F.Fab")
		)
		(pad "1" smd rect
			(at -0.951 -1.049 90)
			(size 1 0.9)
			(layers "F.Cu" "F.Mask" "F.Paste")
			(net 2 "VCC3V3")
			(pinfunction "EN")
			(pintype "input")
		)
		(pad "2" smd rect
			(at -0.951 1.05 90)
			(size 1 0.9)
			(layers "F.Cu" "F.Mask" "F.Paste")
			(net 1 "GND")
			(pinfunction "GND")
			(pintype "power_in")
		)
		(pad "3" smd rect
			(at 0.948 1.05 90)
			(size 1 0.9)
			(layers "F.Cu" "F.Mask" "F.Paste")
			(net 651 "Net-(U17-XI)")
			(pinfunction "OUT")
			(pintype "output")
		)
		(pad "4" smd rect
			(at 0.948 -1.049 90)
			(size 1 0.9)
			(layers "F.Cu" "F.Mask" "F.Paste")
			(net 2 "VCC3V3")
			(pinfunction "VDD")
			(pintype "power_in")
		)
	)
	(footprint "antmicro-footprints:TP_SMD_1mm"
		(layer "F.Cu")
		(at 104.055 164.1058)
		(property "Reference" "TP10"
			(at -2.055 1.5842 0)
			(layer "F.SilkS")
			(effects
				(font
					(size 0.7 0.7)
					(thickness 0.15)
				)
				(justify left bottom)
			)
		)
		(property "Value" "TP_1mm_SMD"
			(at 0 1.4 0)
			(layer "F.Fab")
			(effects
				(font
					(size 0.7 0.7)
					(thickness 0.15)
				)
				(justify left bottom)
			)
		)
		(property "Description" "Test point 1mm SMD"
			(at 0 0 0)
			(layer "F.Fab")
			(hide yes)
			(effects
				(font
					(size 1.27 1.27)
					(thickness 0.15)
				)
			)
		)
		(property "Author" "Antmicro"
			(at 0 0 0)
			(layer "F.Fab")
			(hide yes)
			(effects
				(font
					(size 1 1)
					(thickness 0.15)
				)
			)
		)
		(property "License" "Apache-2.0"
			(at 0 0 0)
			(layer "F.Fab")
			(hide yes)
			(effects
				(font
					(size 1 1)
					(thickness 0.15)
				)
			)
		)
		(property "MPN" ""
			(at 0 0 0)
			(layer "F.Fab")
			(hide yes)
			(effects
				(font
					(size 1 1)
					(thickness 0.15)
				)
			)
		)
		(property "Manufacturer" ""
			(at 0 0 0)
			(layer "F.Fab")
			(hide yes)
			(effects
				(font
					(size 1 1)
					(thickness 0.15)
				)
			)
		)
		(sheetname "/Edge connector/")
		(sheetfile "edge-connector.kicad_sch")
		(attr exclude_from_pos_files exclude_from_bom)
		(fp_circle
			(center 0 0)
			(end 0.6 0)
			(stroke
				(width 0.05)
				(type default)
			)
			(fill no)
			(layer "F.CrtYd")
		)
		(pad "1" smd circle
			(at 0 0)
			(size 1 1)
			(layers "F.Cu" "F.Mask")
			(net 84 "PECI_BMC")
			(pinfunction "1")
			(pintype "passive")
		)
	)
	(footprint "antmicro-footprints:TP_SMD_1mm"
		(layer "F.Cu")
		(at 105.705 164.1158)
		(property "Reference" "TP11"
			(at -0.405 1.5842 0)
			(layer "F.SilkS")
			(effects
				(font
					(size 0.7 0.7)
					(thickness 0.15)
				)
				(justify left bottom)
			)
		)
		(property "Value" "TP_1mm_SMD"
			(at 0 1.4 0)
			(layer "F.Fab")
			(effects
				(font
					(size 0.7 0.7)
					(thickness 0.15)
				)
				(justify left bottom)
			)
		)
		(property "Description" "Test point 1mm SMD"
			(at 0 0 0)
			(layer "F.Fab")
			(hide yes)
			(effects
				(font
					(size 1.27 1.27)
					(thickness 0.15)
				)
			)
		)
		(property "Author" "Antmicro"
			(at 0 0 0)
			(layer "F.Fab")
			(hide yes)
			(effects
				(font
					(size 1 1)
					(thickness 0.15)
				)
			)
		)
		(property "License" "Apache-2.0"
			(at 0 0 0)
			(layer "F.Fab")
			(hide yes)
			(effects
				(font
					(size 1 1)
					(thickness 0.15)
				)
			)
		)
		(property "MPN" ""
			(at 0 0 0)
			(layer "F.Fab")
			(hide yes)
			(effects
				(font
					(size 1 1)
					(thickness 0.15)
				)
			)
		)
		(property "Manufacturer" ""
			(at 0 0 0)
			(layer "F.Fab")
			(hide yes)
			(effects
				(font
					(size 1 1)
					(thickness 0.15)
				)
			)
		)
		(sheetname "/Edge connector/")
		(sheetfile "edge-connector.kicad_sch")
		(attr exclude_from_pos_files exclude_from_bom)
		(fp_circle
			(center 0 0)
			(end 0.6 0)
			(stroke
				(width 0.05)
				(type default)
			)
			(fill no)
			(layer "F.CrtYd")
		)
		(pad "1" smd circle
			(at 0 0)
			(size 1 1)
			(layers "F.Cu" "F.Mask")
			(net 85 "PVCCIO_PECI")
			(pinfunction "1")
			(pintype "passive")
		)
	)
	(footprint "antmicro-footprints:C_0402_1005Metric"
		(layer "F.Cu")
		(at 108.66 95.73 90)
		(descr "Capacitor SMD 0402")
		(tags "capacitor SMD 0402")
		(property "Reference" "C176"
			(at -3.67 0.44 90)
			(layer "F.SilkS")
			(effects
				(font
					(size 0.7 0.7)
					(thickness 0.15)
				)
				(justify left bottom)
			)
		)
		(property "Value" "C_22p_0402"
			(at 0 1.4 90)
			(layer "F.Fab")
			(effects
				(font
					(size 0.7 0.7)
					(thickness 0.15)
				)
				(justify left bottom)
			)
		)
		(property "Datasheet" "https://www.yageo.com/en/Chart/Download/pdf/CC0402JRNPO9BN220"
			(at 0 0 90)
			(layer "F.Fab")
			(hide yes)
			(effects
				(font
					(size 1.27 1.27)
					(thickness 0.15)
				)
			)
		)
		(property "Description" "SMD Multilayer Ceramic Capacitor, 22 pF, 50 V, 0402 [1005 Metric], ± 5%, C0G / NP0, CC Series"
			(at 0 0 90)
			(layer "F.Fab")
			(hide yes)
			(effects
				(font
					(size 1.27 1.27)
					(thickness 0.15)
				)
			)
		)
		(property "Author" "Antmicro"
			(at 204.39 -12.93 0)
			(layer "F.Fab")
			(hide yes)
			(effects
				(font
					(size 1 1)
					(thickness 0.15)
				)
			)
		)
		(property "Dielectric" ""
			(at 204.39 -12.93 0)
			(layer "F.Fab")
			(hide yes)
			(effects
				(font
					(size 1 1)
					(thickness 0.15)
				)
			)
		)
		(property "License" "Apache-2.0"
			(at 204.39 -12.93 0)
			(layer "F.Fab")
			(hide yes)
			(effects
				(font
					(size 1 1)
					(thickness 0.15)
				)
			)
		)
		(property "MPN" "CC0402JRNPO9BN220"
			(at 204.39 -12.93 0)
			(layer "F.Fab")
			(hide yes)
			(effects
				(font
					(size 1 1)
					(thickness 0.15)
				)
			)
		)
		(property "Manufacturer" "YAGEO"
			(at 204.39 -12.93 0)
			(layer "F.Fab")
			(hide yes)
			(effects
				(font
					(size 1 1)
					(thickness 0.15)
				)
			)
		)
		(property "Val" "22p"
			(at 204.39 -12.93 0)
			(layer "F.Fab")
			(hide yes)
			(effects
				(font
					(size 1 1)
					(thickness 0.15)
				)
			)
		)
		(property "Voltage" ""
			(at 204.39 -12.93 0)
			(layer "F.Fab")
			(hide yes)
			(effects
				(font
					(size 1 1)
					(thickness 0.15)
				)
			)
		)
		(sheetname "/Ethernet/")
		(sheetfile "ethernet.kicad_sch")
		(attr smd)
		(fp_rect
			(start -0.925 -0.47)
			(end 0.925 0.47)
			(stroke
				(width 0.05)
				(type default)
			)
			(fill no)
			(layer "F.CrtYd")
		)
		(fp_line
			(start 0.504 -0.25)
			(end 0.504 0.248)
			(stroke
				(width 0.15)
				(type solid)
			)
			(layer "F.Fab")
		)
		(fp_line
			(start -0.494 -0.25)
			(end 0.504 -0.25)
			(stroke
				(width 0.15)
				(type solid)
			)
			(layer "F.Fab")
		)
		(fp_line
			(start 0.504 0.248)
			(end -0.494 0.248)
			(stroke
				(width 0.15)
				(type solid)
			)
			(layer "F.Fab")
		)
		(fp_line
			(start -0.494 0.248)
			(end -0.494 -0.25)
			(stroke
				(width 0.15)
				(type solid)
			)
			(layer "F.Fab")
		)
		(pad "1" smd roundrect
			(at -0.48 0 90)
			(size 0.59 0.64)
			(layers "F.Cu" "F.Mask" "F.Paste")
			(roundrect_rratio 0.25)
			(net 1 "GND")
			(pintype "passive")
		)
		(pad "2" smd roundrect
			(at 0.48 0 90)
			(size 0.59 0.64)
			(layers "F.Cu" "F.Mask" "F.Paste")
			(roundrect_rratio 0.25)
			(net 199 "Net-(U20-XO)")
			(pintype "passive")
		)
	)
	(footprint "antmicro-footprints:C_0402_1005Metric"
		(layer "F.Cu")
		(at 108.65 93.21 -90)
		(descr "Capacitor SMD 0402")
		(tags "capacitor SMD 0402")
		(property "Reference" "C220"
			(at -3.61 -0.45 90)
			(layer "F.SilkS")
			(effects
				(font
					(size 0.7 0.7)
					(thickness 0.15)
				)
				(justify right bottom)
			)
		)
		(property "Value" "C_22p_0402"
			(at 0 1.4 90)
			(layer "F.Fab")
			(effects
				(font
					(size 0.7 0.7)
					(thickness 0.15)
				)
				(justify right bottom)
			)
		)
		(property "Datasheet" "https://www.yageo.com/en/Chart/Download/pdf/CC0402JRNPO9BN220"
			(at 0 0 270)
			(layer "F.Fab")
			(hide yes)
			(effects
				(font
					(size 1.27 1.27)
					(thickness 0.15)
				)
			)
		)
		(property "Description" "SMD Multilayer Ceramic Capacitor, 22 pF, 50 V, 0402 [1005 Metric], ± 5%, C0G / NP0, CC Series"
			(at 0 0 270)
			(layer "F.Fab")
			(hide yes)
			(effects
				(font
					(size 1.27 1.27)
					(thickness 0.15)
				)
			)
		)
		(property "Author" "Antmicro"
			(at 15.44 201.86 0)
			(layer "F.Fab")
			(hide yes)
			(effects
				(font
					(size 1 1)
					(thickness 0.15)
				)
			)
		)
		(property "Dielectric" ""
			(at 15.44 201.86 0)
			(layer "F.Fab")
			(hide yes)
			(effects
				(font
					(size 1 1)
					(thickness 0.15)
				)
			)
		)
		(property "License" "Apache-2.0"
			(at 15.44 201.86 0)
			(layer "F.Fab")
			(hide yes)
			(effects
				(font
					(size 1 1)
					(thickness 0.15)
				)
			)
		)
		(property "MPN" "CC0402JRNPO9BN220"
			(at 15.44 201.86 0)
			(layer "F.Fab")
			(hide yes)
			(effects
				(font
					(size 1 1)
					(thickness 0.15)
				)
			)
		)
		(property "Manufacturer" "YAGEO"
			(at 15.44 201.86 0)
			(layer "F.Fab")
			(hide yes)
			(effects
				(font
					(size 1 1)
					(thickness 0.15)
				)
			)
		)
		(property "Val" "22p"
			(at 15.44 201.86 0)
			(layer "F.Fab")
			(hide yes)
			(effects
				(font
					(size 1 1)
					(thickness 0.15)
				)
			)
		)
		(property "Voltage" ""
			(at 15.44 201.86 0)
			(layer "F.Fab")
			(hide yes)
			(effects
				(font
					(size 1 1)
					(thickness 0.15)
				)
			)
		)
		(sheetname "/Ethernet/")
		(sheetfile "ethernet.kicad_sch")
		(attr smd)
		(fp_rect
			(start -0.925 -0.47)
			(end 0.925 0.47)
			(stroke
				(width 0.05)
				(type default)
			)
			(fill no)
			(layer "F.CrtYd")
		)
		(fp_line
			(start -0.494 0.248)
			(end -0.494 -0.25)
			(stroke
				(width 0.15)
				(type solid)
			)
			(layer "F.Fab")
		)
		(fp_line
			(start 0.504 0.248)
			(end -0.494 0.248)
			(stroke
				(width 0.15)
				(type solid)
			)
			(layer "F.Fab")
		)
		(fp_line
			(start -0.494 -0.25)
			(end 0.504 -0.25)
			(stroke
				(width 0.15)
				(type solid)
			)
			(layer "F.Fab")
		)
		(fp_line
			(start 0.504 -0.25)
			(end 0.504 0.248)
			(stroke
				(width 0.15)
				(type solid)
			)
			(layer "F.Fab")
		)
		(pad "1" smd roundrect
			(at -0.48 0 270)
			(size 0.59 0.64)
			(layers "F.Cu" "F.Mask" "F.Paste")
			(roundrect_rratio 0.25)
			(net 1 "GND")
			(pintype "passive")
		)
		(pad "2" smd roundrect
			(at 0.48 0 270)
			(size 0.59 0.64)
			(layers "F.Cu" "F.Mask" "F.Paste")
			(roundrect_rratio 0.25)
			(net 201 "Net-(U20-XI)")
			(pintype "passive")
		)
	)
	(footprint "antmicro-footprints:R_0402_1005Metric"
		(layer "F.Cu")
		(at 107.64 94.73 90)
		(descr "Resistor SMD 0402")
		(tags "resistor SMD 0402")
		(property "Reference" "R194"
			(at 0.73 0.36 90)
			(layer "F.SilkS")
			(effects
				(font
					(size 0.7 0.7)
					(thickness 0.15)
				)
				(justify left bottom)
			)
		)
		(property "Value" "R_1M8_0402"
			(at 0 1.4 90)
			(layer "F.Fab")
			(effects
				(font
					(size 0.7 0.7)
					(thickness 0.15)
				)
				(justify left bottom)
			)
		)
		(property "Datasheet" "https://www.bourns.com/docs/product-datasheets/cr.pdf"
			(at 0 0 90)
			(layer "F.Fab")
			(hide yes)
			(effects
				(font
					(size 1.27 1.27)
					(thickness 0.15)
				)
			)
		)
		(property "Description" "SMD Chip Resistor"
			(at 0 0 90)
			(layer "F.Fab")
			(hide yes)
			(effects
				(font
					(size 1.27 1.27)
					(thickness 0.15)
				)
			)
		)
		(property "Author" "Antmicro"
			(at 202.37 -12.91 0)
			(layer "F.Fab")
			(hide yes)
			(effects
				(font
					(size 1 1)
					(thickness 0.15)
				)
			)
		)
		(property "License" "Apache-2.0"
			(at 202.37 -12.91 0)
			(layer "F.Fab")
			(hide yes)
			(effects
				(font
					(size 1 1)
					(thickness 0.15)
				)
			)
		)
		(property "MPN" "CR0402-FX-1804GLF"
			(at 202.37 -12.91 0)
			(layer "F.Fab")
			(hide yes)
			(effects
				(font
					(size 1 1)
					(thickness 0.15)
				)
			)
		)
		(property "Manufacturer" "Bourns"
			(at 202.37 -12.91 0)
			(layer "F.Fab")
			(hide yes)
			(effects
				(font
					(size 1 1)
					(thickness 0.15)
				)
			)
		)
		(property "Tolerance" "1%"
			(at 202.37 -12.91 0)
			(layer "F.Fab")
			(hide yes)
			(effects
				(font
					(size 1 1)
					(thickness 0.15)
				)
			)
		)
		(property "Val" "1M8"
			(at 202.37 -12.91 0)
			(layer "F.Fab")
			(hide yes)
			(effects
				(font
					(size 1 1)
					(thickness 0.15)
				)
			)
		)
		(sheetname "/Ethernet/")
		(sheetfile "ethernet.kicad_sch")
		(attr smd)
		(fp_rect
			(start -0.925 -0.47)
			(end 0.925 0.47)
			(stroke
				(width 0.05)
				(type default)
			)
			(fill no)
			(layer "F.CrtYd")
		)
		(fp_rect
			(start -0.5 -0.25)
			(end 0.5 0.25)
			(stroke
				(width 0.15)
				(type solid)
			)
			(fill no)
			(layer "F.Fab")
		)
		(pad "1" smd roundrect
			(at -0.48 0 90)
			(size 0.59 0.64)
			(layers "F.Cu" "F.Mask" "F.Paste")
			(roundrect_rratio 0.25)
			(net 199 "Net-(U20-XO)")
			(pintype "passive")
		)
		(pad "2" smd roundrect
			(at 0.48 0 90)
			(size 0.59 0.64)
			(layers "F.Cu" "F.Mask" "F.Paste")
			(roundrect_rratio 0.25)
			(net 201 "Net-(U20-XI)")
			(pintype "passive")
		)
	)
)
